G04 ================== begin FILE IDENTIFICATION RECORD ==================*
G04 Layout Name:  15968-1a.brd*
G04 Film Name:    L4*
G04 File Format:  Gerber RS274X*
G04 File Origin:  Cadence Allegro 16.5-S058*
G04 Origin Date:  Fri Oct 14 10:26:05 2016*
G04 *
G04 Layer:  VIA CLASS/L4*
G04 Layer:  PIN/L4*
G04 Layer:  ETCH/L4*
G04 Layer:  DRAWING FORMAT/LAYER_PCB_STORY*
G04 Layer:  DRAWING FORMAT/LAYER_L4*
G04 *
G04 Offset:    (0.00 0.00)*
G04 Mirror:    No*
G04 Mode:      Positive*
G04 Rotation:  0*
G04 FullContactRelief:  No*
G04 UndefLineWidth:     6.00*
G04 ================== end FILE IDENTIFICATION RECORD ====================*
%FSLAX35Y35*MOIN*%
%IR0*IPPOS*OFA0.00000B0.00000*MIA0B0*SFA1.00000B1.00000*%
%ADD12C,.02*%
%ADD10C,.022*%
%ADD13C,.042*%
%ADD11C,.155*%
%ADD14C,.012*%
%ADD15C,.025*%
%ADD16C,.005*%
%ADD17C,.006*%
%ADD19C,.03004*%
%ADD23C,.06204*%
%ADD20C,.04404*%
%ADD24C,.06604*%
%ADD18C,.11004*%
%ADD22C,.12504*%
%ADD21C,.17904*%
G75*
%LPD*%
G75*
G36*
G01X76796Y-54400D02*
X75980Y-53584D01*
Y-920D01*
X71883Y3177D01*
X11223D01*
X3150Y11250D01*
Y79850D01*
X38100Y114800D01*
Y148000D01*
X26000Y160100D01*
Y162400D01*
X32200Y168600D01*
X34700D01*
X50200Y153100D01*
Y103900D01*
X28600Y82300D01*
Y77800D01*
X18350Y67550D01*
Y65350D01*
X18000Y65000D01*
Y22500D01*
X24500Y16000D01*
X78500D01*
X94950Y-450D01*
X455700D01*
X457000Y-1750D01*
Y-27500D01*
X454900Y-29600D01*
X99100D01*
X93100Y-35600D01*
Y-51978D01*
G03X92828Y-52912I2806J-1324D01*
G01X92820Y-52980D01*
X91400Y-54400D01*
X76796D01*
G37*
G36*
G01X6901Y106200D02*
X3001Y110100D01*
Y238051D01*
G02X3937Y238987I936J0D01*
G01X104600D01*
Y238400D01*
X106800Y236200D01*
Y232600D01*
X104302Y230102D01*
X40371D01*
X33098Y222829D01*
Y209871D01*
X38571Y204398D01*
X41900D01*
Y196200D01*
X20700Y175000D01*
Y160800D01*
X35800Y145700D01*
Y116500D01*
X25500Y106200D01*
X6901D01*
G37*
G36*
G01X96200Y-63000D02*
X94600Y-61400D01*
Y-54031D01*
X95102Y-53529D01*
Y-38098D01*
X101100Y-32100D01*
X104890D01*
G02X105277Y-32604I1J-400D01*
G03X105670Y-34597I2223J-597D01*
G02X105611Y-35144I-318J-242D01*
G03X108899Y-38336I1489J-1756D01*
G02X109536Y-38351I313J-249D01*
G03X113230Y-35603I1864J1351D01*
G02X113289Y-35056I318J242D01*
G03X113999Y-32618I-1489J1756D01*
G02X114381Y-32100I382J118D01*
G01X456800D01*
X460000Y-28900D01*
Y-1400D01*
X456300Y2300D01*
X382732D01*
G02X382343Y2792I0J400D01*
G03X378057I-2143J508D01*
G02X377668Y2300I-389J-92D01*
G01X161789D01*
G02X161576Y3038I0J400D01*
G03X159224I-1176J1862D01*
G02X159011Y2300I-213J-338D01*
G01X133169D01*
G02X132818Y2892I0J400D01*
G03X129138Y5593I-2018J1108D01*
G02X128576Y5578I-289J277D01*
G03X125257Y5404I-1576J-1678D01*
G02X124665Y5389I-303J261D01*
G03X123619Y6017I-1665J-1589D01*
G01X123569Y6031D01*
X118400Y11200D01*
Y16711D01*
X121989Y20300D01*
X152380D01*
G03X153300Y20098I921J2000D01*
G01X157502D01*
X168800Y8800D01*
X175287D01*
X175688Y8398D01*
X434412D01*
X434813Y8800D01*
X437300D01*
X439982Y11482D01*
X440005Y11495D01*
G03X440805Y12295I-1105J1905D01*
G01X440818Y12318D01*
X441400Y12900D01*
Y15800D01*
X440500Y16700D01*
X431002D01*
G02X430802Y16900I0J200D01*
G03X426398I-2202J0D01*
G02X426198Y16700I-200J0D01*
G01X402953D01*
X380900Y38753D01*
Y42500D01*
X381200Y42800D01*
X452121D01*
G02X452410Y42123I0J-400D01*
G03X455590I1590J-1523D01*
G02X455879Y42800I289J277D01*
G01X461100D01*
X519500Y101200D01*
Y101785D01*
X519550Y101842D01*
G03X519005Y105205I-1650J1458D01*
G01X518982Y105218D01*
X518900Y105300D01*
X518822D01*
X518784Y105317D01*
G03X515788Y103922I-884J-2017D01*
G01X515773Y103873D01*
X515700Y103800D01*
Y103390D01*
G03Y103210I2200J-90D01*
G01Y102100D01*
X515900Y101900D01*
X463944Y49944D01*
G02X463331Y50001I-283J283D01*
G03X463139Y50243I-1817J-1244D01*
G02Y50782I295J270D01*
G03X459887I-1626J1485D01*
G02Y50243I-295J-270D01*
G03X460270Y46940I1626J-1485D01*
G02X460327Y46327I-226J-330D01*
G01X460190Y46190D01*
X406820D01*
G02X406463Y46772I0J400D01*
G03X402537I-1963J997D01*
G02X402180Y46190I-357J-182D01*
G01X386002D01*
G02X385602Y46592I0J400D01*
G03X381198I-2202J8D01*
G02X380798Y46190I-400J-2D01*
G01X374810D01*
X372400Y48600D01*
Y58400D01*
X374248Y60248D01*
X381008D01*
G02X381407Y59813I1J-400D01*
G03X385793I2193J-195D01*
G02X386192Y60248I398J35D01*
G01X396342D01*
X397194Y61100D01*
X398900D01*
X401800Y64000D01*
Y74700D01*
X404249Y77148D01*
X439843D01*
G02X440126Y76467I-1J-400D01*
G03X443250I1562J-1553D01*
G02X443533Y77148I284J281D01*
G01X473730D01*
X474282Y77700D01*
X474600D01*
X514100Y117200D01*
Y117518D01*
X514102Y117520D01*
Y124053D01*
X554828Y164779D01*
Y174872D01*
X554300Y175400D01*
Y176200D01*
X553427Y177073D01*
X553412Y177110D01*
G03X549500Y175118I-2036J-839D01*
G01Y173172D01*
G03X549924Y170363I1876J-1153D01*
G01Y166810D01*
X537914Y154800D01*
X528700D01*
X527000Y156500D01*
Y157079D01*
X527017Y157117D01*
G03X527202Y158000I-2017J883D01*
G01Y173688D01*
X531102Y177588D01*
Y200512D01*
X530057Y201557D01*
G03X526698Y198735I-1558J-1556D01*
G01Y179412D01*
X522798Y175512D01*
Y159034D01*
X520467Y156703D01*
X520390Y156699D01*
G03X518298Y154500I110J-2199D01*
G01Y140135D01*
X505598Y127435D01*
Y121398D01*
X470201Y86002D01*
X469098D01*
X468100Y87000D01*
Y87900D01*
X475800Y95600D01*
Y200500D01*
X461000Y215300D01*
Y219761D01*
G03Y226617I-4742J3428D01*
G01Y234400D01*
X465500Y238900D01*
X602400D01*
X612700Y228600D01*
Y163200D01*
G02X611900Y162400I-850J50D01*
G01X562400D01*
G03X555600Y155800I167J-6975D01*
G01Y9700D01*
G02X555400Y8900I-900J-200D01*
G01X549800Y3300D01*
G02X549115Y3001I-770J830D01*
G01X544176D01*
G03X537000Y-3997I-353J-6816D01*
G01Y-57600D01*
X534900Y-59700D01*
X483700D01*
X483600Y-59600D01*
X444400D01*
X443700Y-58900D01*
Y-40600D01*
X441900Y-38800D01*
X406000D01*
G03X402400Y-42500I101J-3700D01*
G01Y-62500D01*
X401900Y-63000D01*
X191600D01*
X190300Y-61700D01*
Y-52600D01*
G03X174700I-7800J-260D01*
G01Y-62600D01*
X174300Y-63000D01*
X96200D01*
G37*
G36*
G01X112764Y204836D02*
X101200Y216400D01*
X69279D01*
G03X65750Y216417I-1779J-2900D01*
G03X62268Y216428I-1750J-2917D01*
G01X62221Y216400D01*
X61404D01*
X61352Y216438D01*
G03X57797Y216400I-1752J-2438D01*
G01X53200D01*
X43200Y206400D01*
X39400D01*
X35100Y210700D01*
Y222000D01*
X41200Y228100D01*
X114482D01*
X114982Y228600D01*
Y236634D01*
X117335Y238987D01*
X123706D01*
G02X123990Y238306I0J-400D01*
G03X128686I2348J-2322D01*
G02X128970Y238987I284J281D01*
G01X131588D01*
X131786Y238789D01*
G02X131796Y238234I-283J-283D01*
G03X134562Y232700I2417J-2250D01*
G02X135004Y232303I42J-398D01*
G01Y229119D01*
X134995Y229090D01*
G03Y227128I3153J-981D01*
G01X135004Y227099D01*
Y219279D01*
X134995Y219250D01*
G03X134994Y217293I3153J-980D01*
G01X135002Y217264D01*
Y214075D01*
G02X134560Y213678I-400J0D01*
G03X132695Y207461I-348J-3284D01*
G02X132794Y206823I-184J-355D01*
G01X130807Y204836D01*
X112764D01*
G37*
G36*
G01X339998Y37398D02*
X322600Y20000D01*
X178600D01*
X175552Y23048D01*
Y23050D01*
X172502Y26100D01*
Y28951D01*
X172500Y28953D01*
Y33100D01*
X192600Y53200D01*
X231854D01*
G03X235546I1846J1200D01*
G01X260100D01*
X268000Y45300D01*
X336288D01*
G03X337960Y44599I1612J1500D01*
G01X338046Y44601D01*
X339360Y43288D01*
X339712D01*
X341900Y41100D01*
Y40170D01*
X339998Y38268D01*
Y37398D01*
G37*
G36*
G01X361900Y76800D02*
X360500Y78200D01*
Y99500D01*
X357700Y102300D01*
X300890D01*
G03X300710I-90J-2200D01*
G01X201100D01*
X187200Y88400D01*
X166700D01*
X160317Y94783D01*
G02X160423Y95425I283J283D01*
G03X157475Y98373I-973J1975D01*
G02X156833Y98267I-359J177D01*
G01X154400Y100700D01*
Y108463D01*
G03X154461Y108547I-1751J1336D01*
G02X154789I164J-114D01*
G03Y111053I1811J1253D01*
G02X154461I-164J114D01*
G03X154400Y111137I-1812J-1252D01*
G01Y114501D01*
X154402Y114502D01*
Y128269D01*
G02X155129Y128499I400J0D01*
G03X157276Y133649I2704J1895D01*
G02X156926Y134326I-67J394D01*
G01X157100Y134500D01*
Y134600D01*
X158000Y135500D01*
X159974D01*
G03X163524Y135470I1799J2769D01*
G01X163573Y135500D01*
X164900D01*
X167600Y132800D01*
Y127900D01*
X171900Y123600D01*
X179390D01*
G03X183410I2010J900D01*
G01X424600D01*
X424700Y123500D01*
X429300D01*
X433400Y119400D01*
Y103500D01*
X432100Y102200D01*
X367700D01*
X366000Y100500D01*
Y77900D01*
X364900Y76800D01*
X361900D01*
G37*
G36*
G01X139800Y122700D02*
X145500Y128400D01*
Y134569D01*
G02X145913Y134969I400J0D01*
G03X142917Y139389I110J3300D01*
G02X142258Y139242I-376J136D01*
G01X138400Y143100D01*
X132000D01*
X130871Y144229D01*
G02X131059Y144901I283J283D01*
G03X129227Y151239I-781J3208D01*
G02X128700Y151619I-127J379D01*
G01Y153677D01*
G03Y158291I-2362J2307D01*
G01Y191900D01*
X142800Y206000D01*
X147800D01*
X157600Y196200D01*
Y165100D01*
X156952Y164452D01*
X154270D01*
X153918Y164100D01*
X151000D01*
X149400Y162500D01*
Y159242D01*
X149244Y159207D01*
G03X148236Y153170I719J-3223D01*
G02X148309Y152546I-209J-341D01*
G01X147873Y152110D01*
X147043Y151252D01*
X146928Y151285D01*
G03X149167Y149119I-905J-3176D01*
G01X149130Y149234D01*
X149918Y150048D01*
X150531D01*
G02X150895Y149482I0J-400D01*
G03X154098Y151405I3003J-1373D01*
G02X153840Y152087I25J399D01*
G01X155052Y153299D01*
Y153818D01*
X155339D01*
X155399Y153753D01*
G03X160169Y158317I2434J2231D01*
G02X160452Y159000I283J283D01*
G01X161000D01*
X161800Y158200D01*
Y151411D01*
G03Y144807I-27J-3302D01*
G01Y141571D01*
G03X158545Y137574I-27J-3302D01*
G01X158568Y137468D01*
X157900Y136800D01*
X157442D01*
G02X157059Y137315I0J400D01*
G03X154181Y134979I-3161J954D01*
G02X154498Y134298I34J-398D01*
G01X153200Y133000D01*
Y132772D01*
G02X152494Y132515I-400J0D01*
G03Y128273I-2531J-2121D01*
G02X153200Y128016I306J-257D01*
G01Y115000D01*
X150300Y112100D01*
X147200D01*
X147100Y112000D01*
X136200D01*
X132100Y116100D01*
X132700Y116700D01*
Y119800D01*
X134648Y121748D01*
X135358D01*
X136308Y122700D01*
X139800D01*
G37*
G36*
G01X155500Y201700D02*
X153300Y203900D01*
Y212800D01*
X154500Y214000D01*
X156947D01*
X157179Y213768D01*
X157000Y213590D01*
X156950Y213576D01*
G03X161023Y211245I883J-3182D01*
G02X161410Y211748I386J103D01*
G01X162452D01*
X166300Y207900D01*
Y203300D01*
X164700Y201700D01*
X155500D01*
G37*
%LPC*%
G75*
G36*
G01X529383Y221486D02*
G03X529977Y221463I307J256D01*
G02X529817Y217314I2223J-2163D01*
G03X529223Y217337I-307J-256D01*
G02X529383Y221486I-2223J2163D01*
G37*
G36*
G01X567286Y206800D02*
Y206702D01*
X567283Y206607D01*
G02Y206987I-6259J190D01*
G01X567285Y206895D01*
X567286Y206802D01*
Y206800D01*
G37*
G36*
G01X510852Y207928D02*
Y206367D01*
X521750Y195468D01*
X521799Y195454D01*
G02X518085Y191740I-829J-2885D01*
G01X518071Y191789D01*
X505648Y204211D01*
Y205772D01*
X503856Y207565D01*
X503800Y207578D01*
G02X502454Y208269I701J3022D01*
G02X497946I-2254J2131D01*
G03X497661Y208275I-145J-137D01*
G02X493198Y212579I-2161J2225D01*
G03X493186Y213127I-297J268D01*
G02X493215Y217502I2214J2173D01*
G02X497754Y221731I2286J2097D01*
G03X498039Y221725I145J137D01*
G02X502312Y221772I2161J-2225D01*
G03X502591Y221778I136J146D01*
G02X506985Y217398I2209J-2178D01*
G02X506781Y213000I-2285J-2098D01*
G03X506769Y212715I134J-148D01*
G02X507522Y211300I-2269J-2115D01*
G01X507535Y211244D01*
X510852Y207928D01*
G37*
G36*
G01X567286Y190264D02*
Y190166D01*
X567283Y190071D01*
G02Y190451I-6259J190D01*
G01X567285Y190359D01*
X567286Y190266D01*
Y190264D01*
G37*
G36*
G01X390164Y38142D02*
G03X390655Y37834I392J79D01*
G02X389042Y35264I545J-2133D01*
G03X388551Y35572I-392J-79D01*
G02X390164Y38142I-545J2133D01*
G37*
G36*
G01X409870Y25577D02*
G03Y24923I230J-327D01*
G02X407330I-1270J-1799D01*
G03Y25577I-230J327D01*
G02X409276Y29472I1270J1799D01*
G03X409798Y29860I122J381D01*
G02X411324Y27804I2202J40D01*
G03X410802Y27416I-122J-381D01*
G02X409870Y25577I-2202J-40D01*
G37*
G36*
G01X149650Y14960D02*
G03X149615Y14679I123J-158D01*
G02X146528Y15066I-1737J-1353D01*
G03X146563Y15347I-123J158D01*
G02X149650Y14960I1737J1353D01*
G37*
G36*
G01X398949Y-37888D02*
G03X398335I-307J-255D01*
G02Y-35070I-1693J1409D01*
G03X398949I307J255D01*
G02Y-37888I1693J-1409D01*
G37*
G36*
G01X388749D02*
G03X388135I-307J-255D01*
G02Y-35070I-1693J1409D01*
G03X388749I307J255D01*
G02Y-37888I1693J-1409D01*
G37*
G36*
G01X378549D02*
G03X377935I-307J-255D01*
G02Y-35070I-1693J1409D01*
G03X378549I307J255D01*
G02Y-37888I1693J-1409D01*
G37*
G36*
G01X368349D02*
G03X367735I-307J-255D01*
G02Y-35070I-1693J1409D01*
G03X368349I307J255D01*
G02Y-37888I1693J-1409D01*
G37*
G36*
G01X358149D02*
G03X357535I-307J-255D01*
G02Y-35070I-1693J1409D01*
G03X358149I307J255D01*
G02Y-37888I1693J-1409D01*
G37*
G36*
G01X347949D02*
G03X347335I-307J-255D01*
G02Y-35070I-1693J1409D01*
G03X347949I307J255D01*
G02Y-37888I1693J-1409D01*
G37*
G36*
G01X337749D02*
G03X337135I-307J-255D01*
G02Y-35070I-1693J1409D01*
G03X337749I307J255D01*
G02Y-37888I1693J-1409D01*
G37*
G36*
G01X327549D02*
G03X326935I-307J-255D01*
G02Y-35070I-1693J1409D01*
G03X327549I307J255D01*
G02Y-37888I1693J-1409D01*
G37*
G36*
G01X112758Y-50881D02*
G03X112729Y-51473I254J-309D01*
G02X109236Y-54451I-1630J-1626D01*
G03X108599Y-54436I-324J-234D01*
G02X105342Y-51219I-1799J1435D01*
G03X105371Y-50627I-254J309D01*
G02X108864Y-47649I1630J1626D01*
G03X109501Y-47664I324J234D01*
G02X112758Y-50881I1799J-1435D01*
G37*
G54D19*
X324021Y-46464D03*
X334221D03*
X344421D03*
X320021D03*
X330221D03*
X340421D03*
X354621D03*
X364821D03*
X375021D03*
X385221D03*
X395421D03*
X350621D03*
X360821D03*
X371021D03*
X381221D03*
X391421D03*
G54D23*
X540500Y219500D03*
X519900D03*
G54D20*
X404500Y36300D03*
X409400Y69800D03*
X423500Y37800D03*
X418650Y22850D03*
X435287Y25646D03*
X449400Y26433D03*
X429850Y22950D03*
X524994Y-38000D03*
X530994D03*
X324600Y36900D03*
G54D24*
X122403Y228109D03*
X130278D03*
X122403Y218269D03*
X126338Y210394D03*
X130278Y218269D03*
X134213Y155984D03*
X138148Y148109D03*
X142088Y155984D03*
G54D18*
X14794Y226306D03*
X542107Y17432D03*
X585785Y228866D03*
G54D22*
X539370Y190256D03*
Y206792D03*
G54D21*
X542913Y128150D03*
%LPD*%
G75*
G54D10*
X25700Y89200D03*
X27207Y85293D03*
X24400Y81900D03*
X22300Y85000D03*
X21800Y78600D03*
X21600Y74000D03*
X28200Y160400D03*
X95906Y-53300D03*
X84619Y-27663D03*
X89467Y-47981D03*
X84671Y-44973D03*
X79444Y-46817D03*
X90546Y-41425D03*
X90332Y-30191D03*
X85442Y-39927D03*
X79444Y-41282D03*
X90400Y-36500D03*
X85231Y-34026D03*
X79035Y-30696D03*
X79103Y-35748D03*
X33200Y98700D03*
X30600Y88100D03*
X33700Y91400D03*
X29400Y92300D03*
X32800Y95000D03*
X32400Y160600D03*
X29200Y164000D03*
X33100Y164800D03*
X36000Y161800D03*
X31000Y156900D03*
X44200Y212200D03*
X39200Y212100D03*
X44400Y217400D03*
X39300D03*
X172300Y94300D03*
X169800Y91100D03*
X174900Y90900D03*
X135100Y161900D03*
X155600Y166300D03*
X151700D03*
X134900Y165700D03*
X146165Y120044D03*
X140552Y117907D03*
X136626Y118116D03*
X158100Y116300D03*
X158000Y120900D03*
Y124800D03*
X142500Y203900D03*
X145300Y201100D03*
X148314Y203751D03*
X363700Y78200D03*
X428500Y107700D03*
X424200Y103800D03*
X453500Y-9800D03*
X449900Y-9700D03*
X453400Y-13500D03*
X449800D03*
X453500Y-5700D03*
X449900D03*
X453600Y-2000D03*
X450000Y-1900D03*
X460535Y76560D03*
X456662Y76376D03*
X432100Y103800D03*
X504500Y210600D03*
G54D11*
X15748Y128150D03*
X542913D03*
G54D12*
G01X-84798Y-164972D02*
Y-244972D01*
G01D02*
X1172402D01*
G01X-88798Y-148972D02*
G02I-12000J0D01*
G01X-93948D02*
G02I-6850J0D01*
G01X-100798Y-164972D02*
Y-132972D01*
G01X-84798Y-148972D02*
X-116798D01*
G01X-84798Y-164972D02*
X1172402D01*
G01X-84798Y-200472D02*
X1172402D01*
G01X153300Y22300D02*
X164900D01*
X176600Y10600D01*
X433500D01*
X433900Y11000D01*
G01X149963Y126892D02*
Y130394D01*
G01D02*
Y133896D01*
G01X146461Y130394D02*
X149963D01*
G01X157833Y152482D02*
Y155984D01*
G01D02*
X161335D01*
G01X153898Y144607D02*
Y148109D01*
G01X150396D02*
X153898D01*
G01D02*
X157400D01*
G01X157833Y126892D02*
Y130394D01*
G01D02*
Y133896D01*
G01Y130394D02*
X161335D01*
G01X130278Y214767D02*
Y218269D01*
G01D02*
Y221771D01*
G01X126776Y218269D02*
X130278D01*
G01X126338Y206892D02*
Y210394D01*
G01D02*
Y213896D01*
G01X122836Y210394D02*
X126338D01*
G01D02*
X129840D01*
G01X122403Y214767D02*
Y218269D01*
G01D02*
Y221771D01*
G01X118901Y218269D02*
X122403D01*
G01D02*
X125905D01*
G01X130278Y224607D02*
Y228109D01*
G01D02*
Y231611D01*
G01X126776Y228109D02*
X130278D01*
G01D02*
X133780D01*
G01X126338Y232482D02*
Y235984D01*
G01X122836D02*
X126338D01*
G01D02*
X129840D01*
G01X157833Y206892D02*
Y210394D01*
G01X154331D02*
X157833D01*
G01D02*
X161335D01*
G01X191600Y185600D02*
X191300D01*
X188900Y183200D01*
Y173300D01*
G01X384902Y-164972D02*
Y-244972D01*
G01X439000Y87700D02*
X442900Y83800D01*
X471300D01*
X507800Y120300D01*
Y126523D01*
X520500Y139223D01*
Y154500D01*
G01X522402Y-164972D02*
Y-244972D01*
G01X542913Y118998D02*
Y128150D01*
G01D02*
Y137302D01*
G01X533761Y128150D02*
X542913D01*
G01D02*
X552065D01*
G01X528500Y200000D02*
X528900Y199600D01*
Y178500D01*
X525000Y174600D01*
Y158000D01*
G01X520500Y154500D02*
X521378D01*
X524878Y158000D01*
X525000D01*
G01X637402Y-164972D02*
Y-244972D01*
G01X804902Y-164972D02*
Y-244972D01*
G01X974902Y-164972D02*
Y-244972D01*
G01X1172402Y-164972D02*
Y-244972D01*
G01X1200402Y-148972D02*
G02I-12000J0D01*
G01X1195252D02*
G02I-6850J0D01*
G01X1188402Y-164972D02*
Y-132972D01*
G01X1204402Y-148972D02*
X1172402D01*
X6487Y175762D03*
Y165762D03*
X14947Y175971D03*
Y165971D03*
X22700Y190800D03*
X26300D03*
X26600Y201000D03*
X23000D03*
X6487Y235762D03*
X25453Y235870D03*
X15453D03*
X6487Y225762D03*
Y215762D03*
Y205762D03*
Y195762D03*
Y185762D03*
X14947Y195971D03*
Y185971D03*
X107400Y11300D03*
X98200Y10000D03*
X94042Y9842D03*
X98300Y67500D03*
X104500Y56200D03*
X83200Y60000D03*
X48800Y87100D03*
X100000Y175700D03*
X105400Y153600D03*
X106500Y149000D03*
X105218Y137218D03*
X71500Y168500D03*
X98400Y233100D03*
X35453Y235870D03*
X45453D03*
X55453D03*
X65453D03*
X75453D03*
X84400Y232900D03*
X89600D03*
X94900Y233000D03*
X75591Y202676D03*
X79843D03*
X83500Y189000D03*
X67500Y213500D03*
X64000D03*
X161100Y13600D03*
X126800Y-53409D03*
X135182D03*
X144631D03*
X154080D03*
X163529D03*
X172977D03*
X116900Y-35400D03*
X121801Y16999D03*
X146600Y3400D03*
X159450Y8750D03*
X111018Y11382D03*
X174400Y32500D03*
X153300Y22300D03*
X125000Y93400D03*
X129400Y62200D03*
X169800Y39200D03*
X124100Y78900D03*
X137900Y49400D03*
X152900Y46500D03*
X181700Y72700D03*
X154300Y49600D03*
X117600Y117700D03*
X116176Y156724D03*
X109500Y168752D03*
X175600Y166800D03*
X121700Y117300D03*
X111924Y156724D03*
X109500Y164500D03*
X172000Y166800D03*
X124400Y103100D03*
X181400Y124500D03*
X164200Y205100D03*
X180300Y187200D03*
X179900Y191300D03*
X180000Y198500D03*
X183683Y198517D03*
X240100Y20900D03*
X221900Y5100D03*
X235600Y5300D03*
X247200Y5400D03*
X195200Y5700D03*
X191875Y-53409D03*
X201324D03*
X210773D03*
X220221D03*
X229670D03*
X239119D03*
X248568D03*
X258017D03*
X267466D03*
X252300Y22200D03*
X255900Y35000D03*
X246500Y47900D03*
X200500Y31500D03*
X216300Y46700D03*
X226600Y21400D03*
X193900Y51600D03*
X202800Y50200D03*
X198900Y21200D03*
X230300Y45100D03*
X199400Y81400D03*
X236900Y85800D03*
X233700Y54400D03*
X246800Y112500D03*
X198300Y111700D03*
X188900Y173300D03*
X192200Y166700D03*
X195900Y162100D03*
X191600Y185600D03*
X230500Y191400D03*
X224100Y200100D03*
X254900Y188300D03*
X345042Y-41479D03*
X339942D03*
X324642D03*
X334842D03*
X329742D03*
X319070Y-41541D03*
X276914Y-53409D03*
X286363D03*
X295812D03*
X305261D03*
X314710D03*
X324158D03*
X333607D03*
X343056D03*
X328000Y30500D03*
X339649Y41539D03*
X300800Y100100D03*
X337900Y46800D03*
X313400Y119100D03*
X327200Y178276D03*
Y174024D03*
X294600Y201300D03*
X332000Y192200D03*
X329400Y195900D03*
X321600Y186300D03*
X323243Y183323D03*
X396042Y-41479D03*
X390942D03*
X380742D03*
X385842D03*
X375642D03*
X370542D03*
X365442D03*
X360342D03*
X355242D03*
X401142D03*
X350142D03*
X423852Y4375D03*
X420252Y-36925D03*
X410052Y-36825D03*
X352505Y-53409D03*
X361954D03*
X371403D03*
X380851D03*
X390300D03*
X399815Y-52741D03*
X415100Y3400D03*
X352600Y7600D03*
X380200Y6800D03*
X405500Y29200D03*
X383300Y50700D03*
X388000Y41600D03*
X394500Y34000D03*
X405800Y21100D03*
X420322Y56072D03*
X423202Y56119D03*
X426128Y50188D03*
Y53348D03*
X426065Y56213D03*
X426113Y59046D03*
X425971Y62050D03*
X423500Y34200D03*
X416300Y37100D03*
X418705Y34695D03*
X405569Y72731D03*
X409026Y61211D03*
X383600Y55532D03*
X401211Y46589D03*
X384000Y41600D03*
X391600Y29400D03*
X383500Y69200D03*
X349701Y64199D03*
X353100Y63900D03*
X355300Y81400D03*
X398805Y66200D03*
X395406Y66092D03*
X402500Y89124D03*
X375514Y85000D03*
X402500Y93376D03*
X372114Y85000D03*
X358700Y38100D03*
X362100D03*
X372400Y41100D03*
X436752Y4175D03*
X498052Y-625D03*
X490200Y-6400D03*
X488652Y-18225D03*
X496352Y-19025D03*
X432452Y-36225D03*
X447252Y-47725D03*
X445252Y-37225D03*
X455701Y-53425D03*
X502945D03*
X493496D03*
X484047D03*
X474598D03*
X465149D03*
X446252D03*
X433900Y11000D03*
X438900Y13400D03*
X469300Y87600D03*
X459652Y31575D03*
X458100Y47300D03*
Y53700D03*
X432091Y56151D03*
X429056Y56135D03*
X457400Y41800D03*
X468588Y55981D03*
X431382Y35283D03*
X454085Y63272D03*
X452496Y70099D03*
X454500Y29300D03*
X439418Y26110D03*
X439000Y87700D03*
X451381Y88210D03*
Y91719D03*
X457245Y105151D03*
X453736D03*
X466361Y230936D03*
X467506Y226106D03*
X502000Y229400D03*
X466010Y216328D03*
X492961Y227336D03*
X480761Y227936D03*
X505961Y236936D03*
X488161Y236336D03*
X479761D03*
X499761D03*
X455700Y205800D03*
X528590Y-12237D03*
Y2763D03*
X532137Y7890D03*
X532691Y-17725D03*
X531600Y-31800D03*
X523300Y-32100D03*
X531291Y-53425D03*
X521842D03*
X512393D03*
X534737Y40290D03*
X534337Y52790D03*
X534637Y74290D03*
Y92590D03*
X532778Y21738D03*
X512000Y158400D03*
X511900Y174400D03*
Y142700D03*
X521900Y179500D03*
X548200Y169900D03*
X548300Y178100D03*
X578337Y166890D03*
X577748Y181113D03*
X529000Y158500D03*
X521600Y158400D03*
X520500Y154500D03*
X525000Y158000D03*
X551376Y176271D03*
Y172019D03*
X517900Y103300D03*
X524200Y181600D03*
X519700Y181900D03*
X521900Y184000D03*
X545300Y236800D03*
X529500Y236400D03*
X519761Y236336D03*
X537200Y236400D03*
X559761Y236336D03*
X579761D03*
X577748Y211113D03*
X578337Y226890D03*
X577748Y191113D03*
Y201113D03*
X524000Y200000D03*
X520970Y192569D03*
X528500Y200000D03*
X593337Y166890D03*
Y176890D03*
X608337Y166890D03*
Y176890D03*
X599761Y236336D03*
X593337Y206890D03*
Y216890D03*
Y226890D03*
Y186890D03*
Y196890D03*
X608337Y206890D03*
Y216890D03*
Y226890D03*
Y186890D03*
Y196890D03*
G54D13*
X122403Y148109D03*
X146023D03*
X149963Y155984D03*
X153898Y148109D03*
X157833Y155984D03*
X138148Y138269D03*
X142088Y130394D03*
X149963D03*
X157833D03*
X126338Y235984D03*
X130278Y228109D03*
X146023D03*
X149963Y235984D03*
X122403Y218269D03*
X126338Y210394D03*
X130278Y218269D03*
X138148D03*
X142088Y210394D03*
X157833D03*
X252323Y155984D03*
X256258Y148109D03*
X252323Y235984D03*
X256258Y228109D03*
G54D14*
G01X294600Y201300D02*
X294500Y201400D01*
X284400D01*
X279700Y196700D01*
X237400D01*
X232100Y191400D01*
X230500D01*
G01X504500Y210600D02*
X508250Y206850D01*
Y205289D01*
X520970Y192569D01*
G54D15*
G01X125000Y93400D02*
X99100Y67500D01*
X98300D01*
G01X363700Y78200D02*
X364300D01*
G01D02*
X373300Y69200D01*
X383500D01*
G54D16*
G01X98200Y10000D02*
X96900Y11300D01*
Y56840D01*
X96901Y56841D01*
Y63528D01*
X87201Y73228D01*
Y81272D01*
X99500Y93571D01*
Y104229D01*
X92700Y111029D01*
Y142129D01*
X64110Y170719D01*
Y207161D01*
X66500Y209551D01*
Y212500D01*
X67500Y213500D01*
G01X94042Y9842D02*
X94900Y10700D01*
Y62700D01*
X85200Y72400D01*
Y82100D01*
X97400Y94300D01*
Y103500D01*
X90700Y110200D01*
Y141300D01*
X62110Y169890D01*
Y207990D01*
X64500Y210380D01*
Y213000D01*
X64000Y213500D01*
G01X137900Y49400D02*
X137500Y49000D01*
X134200D01*
X129100Y54100D01*
X106600D01*
X104500Y56200D01*
G01D02*
Y60400D01*
X109600Y65500D01*
X110700D01*
X124100Y78900D01*
G01X83200Y60000D02*
Y82200D01*
X77600Y87800D01*
X62500D01*
G01D02*
X49500D01*
X48800Y87100D01*
G01X122403Y148109D02*
X121605Y149005D01*
X121200Y149410D01*
Y157400D01*
X117000Y161600D01*
X107000D01*
X104200Y164400D01*
Y171800D01*
X100300Y175700D01*
X100000D01*
G01X117600Y117700D02*
Y120600D01*
X107700Y130500D01*
Y141171D01*
X104500Y144371D01*
Y151252D01*
X105400Y152152D01*
Y153600D01*
G01X75591Y202676D02*
X77083Y201184D01*
Y201088D01*
X89450Y188721D01*
Y172121D01*
X90035Y171536D01*
Y171535D01*
X105400Y156170D01*
Y153600D01*
G01X121700Y117300D02*
Y119329D01*
X109700Y131329D01*
Y142000D01*
X106500Y145200D01*
Y149000D01*
G01X79843Y202676D02*
Y201157D01*
X91450Y189550D01*
Y172950D01*
X92035Y172365D01*
Y172364D01*
X108500Y155899D01*
Y151000D01*
X106500Y149000D01*
G01X105218Y137218D02*
Y140282D01*
X86500Y159000D01*
Y186000D01*
X83500Y189000D01*
G01X124400Y103100D02*
Y105600D01*
X105218Y124782D01*
Y137218D01*
G01X181700Y72700D02*
X170600D01*
X142500Y100800D01*
X106600D01*
X94900Y112500D01*
Y147100D01*
X73500Y168500D01*
X71500D01*
G01X438900Y13400D02*
X404200D01*
X374211Y43389D01*
X351189D01*
X346550Y38750D01*
X344362D01*
X344291Y38821D01*
X342757D01*
X342686Y38750D01*
X342533D01*
X341450Y37667D01*
Y33650D01*
X325400Y17600D01*
X178800D01*
X174100Y22300D01*
Y22449D01*
X171050Y25499D01*
Y28350D01*
X152900Y46500D01*
G01X358700Y38100D02*
Y34683D01*
X339267Y15250D01*
X238594D01*
X238544Y15300D01*
X177900D01*
X164100Y29100D01*
X125200D01*
X107400Y11300D01*
G01X362100Y38100D02*
X360300Y36300D01*
Y34444D01*
X339356Y13500D01*
X178900D01*
X178400Y14000D01*
X177361D01*
X166811Y24550D01*
X124186D01*
X111018Y11382D01*
G01X169800Y39200D02*
Y55700D01*
X159500Y66000D01*
X133200D01*
X129400Y62200D01*
G01X117600Y117700D02*
Y116471D01*
X128071Y106000D01*
X143371D01*
X164771Y84600D01*
X199771D01*
X206371Y91200D01*
X332971D01*
X362471Y61700D01*
X395741D01*
X398805Y64764D01*
Y66200D01*
G01X121700Y117300D02*
X131000Y108000D01*
X144200D01*
X165600Y86600D01*
X198942D01*
X205542Y93200D01*
X333800D01*
X363300Y63700D01*
X394912D01*
X396105Y64893D01*
Y65393D01*
X395406Y66092D01*
G01X124400Y103100D02*
X124600Y103300D01*
X142500D01*
X165500Y80300D01*
X180500D01*
X203800Y57000D01*
X260500D01*
X270700Y46800D01*
X337900D01*
G01X154300Y49600D02*
X166550Y37350D01*
X174150D01*
X192100Y55300D01*
X232800D01*
X233700Y54400D01*
G01X116176Y156724D02*
X115100Y155648D01*
Y134049D01*
X123949Y125200D01*
X133927D01*
X137186Y128462D01*
X137195Y128486D01*
X137197Y128491D01*
X137198Y128494D01*
X137302Y128765D01*
X137529Y129128D01*
X137697Y129397D01*
X137865Y129576D01*
X138094Y129817D01*
X138200Y129924D01*
Y134144D01*
X139100Y135044D01*
Y136464D01*
X138704Y137255D01*
X138148Y138269D01*
G01X109500Y168752D02*
X109552D01*
X111100Y170300D01*
Y180757D01*
X137654Y207311D01*
Y217776D01*
X138148Y218269D01*
G01X146023Y148109D02*
X148908Y151092D01*
X149316Y151500D01*
X151200D01*
X153600Y153900D01*
Y158900D01*
X155700Y161000D01*
X170500D01*
X175600Y166100D01*
Y166800D01*
G01X142088Y130394D02*
Y129660D01*
X141321Y128893D01*
X141156Y128889D01*
X140897D01*
X140533Y128880D01*
X140177Y128799D01*
X139844Y128651D01*
X139605Y128483D01*
X139552Y128446D01*
X139527Y128421D01*
X139321Y128204D01*
X139292Y128173D01*
X139226Y128067D01*
X139101Y127868D01*
X139066Y127777D01*
X139063Y127768D01*
X138902Y127349D01*
X134756Y123200D01*
X123120D01*
X113100Y133220D01*
Y155548D01*
X111924Y156724D01*
G01X142088Y210394D02*
X139654Y207960D01*
Y206482D01*
X113100Y179928D01*
Y168100D01*
X109500Y164500D01*
G01X149963Y155984D02*
X151600Y157900D01*
Y159729D01*
X154871Y163000D01*
X169500D01*
X172000Y165500D01*
Y166800D01*
G01X254900Y188300D02*
X247400Y180800D01*
X212600D01*
X211600Y181800D01*
X195600D01*
X193500Y179700D01*
Y173400D01*
X185300Y165200D01*
Y154100D01*
X189100Y150300D01*
Y135300D01*
X185600Y131800D01*
Y128700D01*
X181400Y124500D01*
G01X455700Y205800D02*
X440050Y190150D01*
X254133D01*
X253583Y189600D01*
X244539D01*
X238989Y184050D01*
X220811D01*
X216761Y188100D01*
X181200D01*
X180300Y187200D01*
G01X179900Y191300D02*
X180200Y191600D01*
X215100D01*
X218450Y188250D01*
X241350D01*
X244000Y190900D01*
X253044D01*
X254344Y192200D01*
X332000D01*
G01X146023Y228109D02*
X147434Y230930D01*
X147970Y231108D01*
X148329Y230929D01*
X149100Y230158D01*
Y225700D01*
X152000Y222800D01*
X155000D01*
X157000Y220800D01*
Y216000D01*
X159800Y213200D01*
X166600D01*
X167900Y214500D01*
X174200D01*
X176700Y212000D01*
Y207200D01*
X180200Y203700D01*
Y198700D01*
X180000Y198500D01*
G01X183683Y198517D02*
X182200Y200000D01*
Y204600D01*
X178300Y208500D01*
Y212500D01*
X174600Y216200D01*
X167195D01*
X165895Y214900D01*
X160505D01*
X158700Y216705D01*
Y221505D01*
X155705Y224500D01*
X152705D01*
X150800Y226405D01*
Y230863D01*
X149336Y232328D01*
X149049Y232471D01*
X148733Y232629D01*
X148553Y233165D01*
X149963Y235984D01*
G01X199400Y81400D02*
X207200Y89200D01*
X311700D01*
X336701Y64199D01*
X349701D01*
G01X353100Y63900D02*
X350700Y61500D01*
X261200D01*
X236900Y85800D01*
G01X256258Y148109D02*
X254828Y150972D01*
X255053Y151643D01*
X255499Y151866D01*
X256066Y152148D01*
X256318Y153104D01*
X256888Y155271D01*
X257115Y158527D01*
X258768Y161932D01*
X262536Y165700D01*
X264036D01*
X264926Y164810D01*
X266426D01*
X267316Y165700D01*
X268816D01*
X269706Y164810D01*
X271206D01*
X272096Y165700D01*
X273596D01*
X274486Y164810D01*
X275986D01*
X276876Y165700D01*
X296876D01*
X297766Y164810D01*
X299266D01*
X300156Y165700D01*
X301656D01*
X302546Y164810D01*
X304046D01*
X304936Y165700D01*
X306436D01*
X307326Y164810D01*
X308826D01*
X309716Y165700D01*
X329716D01*
X330606Y164810D01*
X332106D01*
X332996Y165700D01*
X334496D01*
X335386Y164810D01*
X336886D01*
X337776Y165700D01*
X339276D01*
X340166Y164810D01*
X341666D01*
X342556Y165700D01*
X362556D01*
X363446Y164810D01*
X364946D01*
X365836Y165700D01*
X367336D01*
X368226Y164810D01*
X369726D01*
X370616Y165700D01*
X453592D01*
X462900Y156392D01*
Y105380D01*
X459920Y102400D01*
X457300D01*
X456300Y103400D01*
Y104206D01*
X457245Y105151D01*
G01X252323Y155984D02*
X253754Y153119D01*
X254425Y152896D01*
X254428Y152897D01*
X254873Y153119D01*
X255500Y155500D01*
X255717Y158624D01*
X255718D01*
X255737Y158895D01*
X257611Y162755D01*
X261956Y167100D01*
X454172D01*
X464300Y156972D01*
Y104800D01*
X460500Y101000D01*
X456720D01*
X454900Y102820D01*
Y103987D01*
X453736Y105151D01*
G01X192200Y166700D02*
X194200D01*
X195600Y168100D01*
Y171029D01*
X202716Y178145D01*
X204372D01*
X204373Y178144D01*
X313444D01*
X321600Y186300D01*
G01X195900Y162100D02*
Y162800D01*
X197600Y164500D01*
Y170200D01*
X203544Y176144D01*
X314273D01*
X321452Y183323D01*
X323243D01*
G01X451381Y88210D02*
X452436Y89265D01*
X453936D01*
X454826Y88375D01*
X456326D01*
X457216Y89265D01*
X458716D01*
X459606Y88375D01*
X461106D01*
X461996Y89265D01*
X465945D01*
X473100Y96420D01*
Y197280D01*
X446480Y223900D01*
X253900D01*
X253068Y224732D01*
Y230334D01*
X253709Y230975D01*
X253928Y231084D01*
X254153Y231196D01*
X254156Y231197D01*
X254827Y230974D01*
X256258Y228109D01*
G01X451381Y91719D02*
X452435Y90665D01*
X465365D01*
X471700Y97000D01*
Y196700D01*
X445900Y222500D01*
X253320D01*
X251668Y224152D01*
Y230914D01*
X252880Y232126D01*
X253528Y232450D01*
X253753Y233121D01*
X252323Y235984D01*
G01X329400Y195900D02*
X328900Y195400D01*
X298361D01*
X297011Y194050D01*
X251667D01*
X250867Y194850D01*
X246111D01*
X240811Y189550D01*
X229733D01*
X224100Y195183D01*
Y200100D01*
G01X355300Y81400D02*
X336433Y100267D01*
X300967D01*
X300800Y100100D01*
G01X337900Y46800D02*
X339961Y44739D01*
X460959D01*
X517900Y101680D01*
Y103300D01*
G01X327200Y178276D02*
X328326Y177150D01*
X454279D01*
X469000Y162429D01*
Y101400D01*
X463300Y95700D01*
X421729D01*
X416179Y90150D01*
X403526D01*
X402500Y89124D01*
G01X327200Y174024D02*
X328326Y175150D01*
X453450D01*
X467000Y161600D01*
Y102229D01*
X462471Y97700D01*
X420900D01*
X415350Y92150D01*
X403726D01*
X402500Y93376D01*
G01X398805Y66200D02*
X398100Y66905D01*
Y73729D01*
X402971Y78600D01*
X473129D01*
X512650Y118121D01*
Y124654D01*
X553376Y165380D01*
Y174271D01*
X551376Y176271D01*
G01X395406Y66092D02*
Y66706D01*
X396100Y67400D01*
Y74558D01*
X402143Y80601D01*
X403799D01*
X403800Y80600D01*
X472300D01*
X510650Y118950D01*
Y125483D01*
X551376Y166209D01*
Y172019D01*
G01X402500Y89124D02*
X401374Y90250D01*
X375974D01*
X375033Y89309D01*
Y85481D01*
X375514Y85000D01*
G01X402500Y93376D02*
X402376D01*
X401250Y92250D01*
X375145D01*
X373033Y90138D01*
Y85919D01*
X372114Y85000D01*
G01X372400Y41100D02*
X365100D01*
X362100Y38100D01*
G54D17*
G01X-65001Y-234972D02*
Y-217472D01*
X-60635D01*
X-58888Y-218347D01*
X-57578Y-219514D01*
X-56486Y-221263D01*
X-55613Y-223306D01*
X-55395Y-226222D01*
X-55613Y-229139D01*
X-56486Y-231181D01*
X-57578Y-232931D01*
X-58888Y-234097D01*
X-60635Y-234972D01*
X-65001D01*
G01X-48157Y-217472D02*
X-42698Y-234972D01*
X-37239Y-217472D01*
G01X-25198D02*
Y-234972D01*
G01X-30220Y-217472D02*
X-20176D01*
G01X5435Y-234972D02*
Y-217472D01*
X10894D01*
X12640Y-218347D01*
X13732Y-219514D01*
X14169Y-221847D01*
X13732Y-224181D01*
X12422Y-225639D01*
X10894Y-226514D01*
X5435D01*
G01X10894D02*
X14169Y-234972D01*
G01X27302Y-223306D02*
Y-234972D01*
G01Y-218639D02*
X26865Y-218347D01*
Y-217764D01*
X27302Y-217472D01*
X27739Y-217764D01*
Y-218347D01*
X27302Y-218639D01*
G01X41527Y-232931D02*
X42619Y-234097D01*
X44147Y-234972D01*
X45457D01*
X46767Y-234389D01*
X47640Y-233514D01*
X48077Y-232348D01*
X47859Y-230597D01*
X46985Y-229722D01*
X43055Y-227972D01*
X42182Y-225930D01*
X42619Y-224472D01*
X43492Y-223597D01*
X44802Y-223306D01*
X46112Y-223597D01*
X47422Y-224472D01*
G01X59027Y-227097D02*
X66014D01*
X65359Y-225055D01*
X64267Y-223889D01*
X62739Y-223306D01*
X61210Y-223597D01*
X59900Y-224472D01*
X59027Y-226514D01*
X58590Y-228264D01*
Y-230014D01*
X59027Y-231764D01*
X60119Y-233514D01*
X61429Y-234680D01*
X62957Y-234972D01*
X64485Y-234389D01*
X66014Y-232639D01*
G01X76745Y-234972D02*
Y-223306D01*
G01Y-225639D02*
X77837Y-224472D01*
X78929Y-223597D01*
X80457Y-223306D01*
X81548Y-223597D01*
X82859Y-224472D01*
G01X119605Y-218931D02*
X118295Y-218055D01*
X116767Y-217472D01*
X115020D01*
X113055Y-218347D01*
X111527Y-219805D01*
X110435Y-221556D01*
X109562Y-224472D01*
X109343Y-227097D01*
X109780Y-229722D01*
X110435Y-231472D01*
X111745Y-233222D01*
X113274Y-234389D01*
X114802Y-234972D01*
X116330D01*
X117859Y-234389D01*
X119169Y-233514D01*
X120261Y-232348D01*
G01X136232Y-234972D02*
Y-223306D01*
G01Y-225347D02*
X135359Y-224181D01*
X134048Y-223597D01*
X132520Y-223306D01*
X130992Y-223889D01*
X129682Y-225055D01*
X128808Y-226805D01*
X128372Y-229139D01*
X128808Y-231472D01*
X129682Y-233222D01*
X130992Y-234389D01*
X132520Y-234972D01*
X134048Y-234680D01*
X135359Y-233806D01*
X136232Y-232639D01*
G01X146745Y-234972D02*
Y-223306D01*
G01Y-225639D02*
X147837Y-224472D01*
X148929Y-223597D01*
X150457Y-223306D01*
X151548Y-223597D01*
X152859Y-224472D01*
G01X171232Y-217472D02*
Y-234972D01*
G01Y-232348D02*
X170359Y-233806D01*
X169048Y-234680D01*
X167520Y-234972D01*
X165774Y-234389D01*
X164464Y-232931D01*
X163590Y-231181D01*
X163372Y-229139D01*
X163590Y-227097D01*
X164464Y-225347D01*
X165774Y-223889D01*
X167520Y-223306D01*
X169048Y-223597D01*
X170140Y-224181D01*
X171232Y-225347D01*
G01X178252Y-240805D02*
X191352D01*
G01X197717Y-232639D02*
X199464Y-234097D01*
X201429Y-234972D01*
X203175D01*
X204922Y-234097D01*
X206232Y-232639D01*
X206887Y-230597D01*
X206450Y-228556D01*
X205359Y-226805D01*
X203394Y-225639D01*
X200774Y-225055D01*
X199245Y-223889D01*
X198590Y-221847D01*
X199027Y-219805D01*
X200119Y-218347D01*
X201647Y-217472D01*
X203175D01*
X204704Y-218055D01*
X206014Y-219514D01*
G01X215217Y-232639D02*
X216964Y-234097D01*
X218929Y-234972D01*
X220675D01*
X222422Y-234097D01*
X223732Y-232639D01*
X224387Y-230597D01*
X223950Y-228556D01*
X222859Y-226805D01*
X220894Y-225639D01*
X218274Y-225055D01*
X216745Y-223889D01*
X216090Y-221847D01*
X216527Y-219805D01*
X217619Y-218347D01*
X219147Y-217472D01*
X220675D01*
X222204Y-218055D01*
X223514Y-219514D01*
G01X250654Y-220389D02*
X251964Y-218639D01*
X253492Y-217764D01*
X255239Y-217472D01*
X257422Y-218055D01*
X258950Y-219514D01*
X259387Y-221263D01*
X259169Y-223014D01*
X258295Y-224472D01*
X253929Y-227389D01*
X251964Y-229430D01*
X250654Y-232348D01*
X250217Y-234972D01*
X259387D01*
G01X286527Y-232931D02*
X287619Y-234097D01*
X289147Y-234972D01*
X290457D01*
X291767Y-234389D01*
X292640Y-233514D01*
X293077Y-232348D01*
X292859Y-230597D01*
X291985Y-229722D01*
X288055Y-227972D01*
X287182Y-225930D01*
X287619Y-224472D01*
X288492Y-223597D01*
X289802Y-223306D01*
X291112Y-223597D01*
X292422Y-224472D01*
G01X307302Y-234972D02*
Y-217472D01*
G01X324802Y-234972D02*
X323492Y-234680D01*
X322182Y-233514D01*
X321308Y-231472D01*
X320872Y-229139D01*
X321308Y-226805D01*
X322182Y-224764D01*
X323492Y-223597D01*
X324802Y-223306D01*
X326112Y-223597D01*
X327422Y-224764D01*
X328295Y-226805D01*
X328514Y-229139D01*
X328295Y-231472D01*
X327422Y-233514D01*
X326112Y-234680D01*
X324802Y-234972D01*
G01X342302Y-217472D02*
Y-234972D01*
G01X339245Y-223306D02*
X345359D01*
G01X356527Y-232931D02*
X357619Y-234097D01*
X359147Y-234972D01*
X360457D01*
X361767Y-234389D01*
X362640Y-233514D01*
X363077Y-232348D01*
X362859Y-230597D01*
X361985Y-229722D01*
X358055Y-227972D01*
X357182Y-225930D01*
X357619Y-224472D01*
X358492Y-223597D01*
X359802Y-223306D01*
X361112Y-223597D01*
X362422Y-224472D01*
G01X109125Y-189972D02*
Y-172472D01*
X114802Y-187055D01*
X120479Y-172472D01*
Y-189972D01*
G01X132302D02*
X130992Y-189680D01*
X129682Y-188514D01*
X128808Y-186472D01*
X128372Y-184139D01*
X128808Y-181805D01*
X129682Y-179764D01*
X130992Y-178597D01*
X132302Y-178306D01*
X133612Y-178597D01*
X134922Y-179764D01*
X135795Y-181805D01*
X136014Y-184139D01*
X135795Y-186472D01*
X134922Y-188514D01*
X133612Y-189680D01*
X132302Y-189972D01*
G01X153732Y-172472D02*
Y-189972D01*
G01Y-187348D02*
X152859Y-188806D01*
X151548Y-189680D01*
X150020Y-189972D01*
X148274Y-189389D01*
X146964Y-187931D01*
X146090Y-186181D01*
X145872Y-184139D01*
X146090Y-182097D01*
X146964Y-180347D01*
X148274Y-178889D01*
X150020Y-178306D01*
X151548Y-178597D01*
X152640Y-179181D01*
X153732Y-180347D01*
G01X164027Y-182097D02*
X171014D01*
X170359Y-180055D01*
X169267Y-178889D01*
X167739Y-178306D01*
X166210Y-178597D01*
X164900Y-179472D01*
X164027Y-181514D01*
X163590Y-183264D01*
Y-185014D01*
X164027Y-186764D01*
X165119Y-188514D01*
X166429Y-189680D01*
X167957Y-189972D01*
X169485Y-189389D01*
X171014Y-187639D01*
G01X184802Y-189972D02*
Y-172472D01*
G01X418602Y-234972D02*
Y-217472D01*
X415982Y-220972D01*
G01Y-234972D02*
X421222D01*
G01X431299Y-232348D02*
X432608Y-233806D01*
X434137Y-234680D01*
X436102Y-234972D01*
X438067Y-234389D01*
X439595Y-233222D01*
X440687Y-231181D01*
X440905Y-228847D01*
X440469Y-226514D01*
X439377Y-225055D01*
X437848Y-223889D01*
X436320Y-223597D01*
X434792Y-223889D01*
X432827Y-225055D01*
X433482Y-217472D01*
X439377D01*
G01X449890Y-232931D02*
X451419Y-234389D01*
X453165Y-234972D01*
X454912Y-234389D01*
X456440Y-232639D01*
X457532Y-230014D01*
X457969Y-227389D01*
Y-224181D01*
X457532Y-221556D01*
X456440Y-219222D01*
X455130Y-218055D01*
X453602Y-217472D01*
X451855Y-218055D01*
X450545Y-219222D01*
X449672Y-220972D01*
X449235Y-223306D01*
X449672Y-225347D01*
X450764Y-227389D01*
X452074Y-228556D01*
X453602Y-228847D01*
X455348Y-228264D01*
X456659Y-226805D01*
X457969Y-224181D01*
G01X466954Y-227681D02*
X468482Y-225639D01*
X469792Y-224472D01*
X471539Y-223889D01*
X473067Y-224472D01*
X474159Y-225639D01*
X475032Y-227389D01*
X475250Y-229430D01*
X475032Y-231181D01*
X474159Y-232931D01*
X472848Y-234389D01*
X471320Y-234972D01*
X469574Y-234389D01*
X468045Y-232639D01*
X467172Y-230014D01*
X466954Y-227097D01*
X467390Y-223306D01*
X468045Y-221263D01*
X469137Y-219222D01*
X470665Y-217764D01*
X472194Y-217472D01*
X473722Y-218055D01*
X474814Y-219514D01*
G01X488602Y-234972D02*
X490130Y-234680D01*
X491877Y-233806D01*
X492969Y-232348D01*
X493405Y-230305D01*
X492969Y-228264D01*
X491659Y-226514D01*
X489694Y-225639D01*
X487510D01*
X486200Y-225055D01*
X485108Y-223597D01*
X484672Y-221556D01*
X485327Y-219514D01*
X486855Y-218055D01*
X488602Y-217472D01*
X490348Y-218055D01*
X491877Y-219514D01*
X492532Y-221556D01*
X492095Y-223597D01*
X491004Y-225055D01*
X489694Y-225639D01*
X487510D01*
X485545Y-226514D01*
X484235Y-228264D01*
X483799Y-230305D01*
X484235Y-232348D01*
X485327Y-233806D01*
X487074Y-234680D01*
X488602Y-234972D01*
G01X405485Y-189972D02*
Y-172472D01*
X410725D01*
X412472Y-173347D01*
X413782Y-175389D01*
X414219Y-177722D01*
X413782Y-180055D01*
X412690Y-181805D01*
X410725Y-182681D01*
X405485D01*
G01X432155Y-173931D02*
X430845Y-173055D01*
X429317Y-172472D01*
X427570D01*
X425605Y-173347D01*
X424077Y-174805D01*
X422985Y-176556D01*
X422112Y-179472D01*
X421893Y-182097D01*
X422330Y-184722D01*
X422985Y-186472D01*
X424295Y-188222D01*
X425824Y-189389D01*
X427352Y-189972D01*
X428880D01*
X430409Y-189389D01*
X431719Y-188514D01*
X432811Y-187348D01*
G01X446598Y-180639D02*
X447472Y-179764D01*
X448127Y-178306D01*
X448564Y-176263D01*
X448127Y-174514D01*
X447254Y-173347D01*
X445725Y-172472D01*
X439830D01*
Y-189972D01*
X447035D01*
X448564Y-188806D01*
X449437Y-187055D01*
X449874Y-185014D01*
X449437Y-182972D01*
X448127Y-181222D01*
X446598Y-180639D01*
X439830D01*
G01X455802Y-195805D02*
X468902D01*
G01X474830Y-189972D02*
Y-172472D01*
X484874Y-189972D01*
Y-172472D01*
G01X497352Y-189972D02*
X495605Y-189680D01*
X494077Y-188514D01*
X492767Y-186764D01*
X491893Y-184722D01*
X491457Y-182389D01*
Y-180055D01*
X491893Y-177722D01*
X492767Y-175680D01*
X494077Y-173931D01*
X495605Y-172764D01*
X497352Y-172472D01*
X499098Y-172764D01*
X500627Y-173931D01*
X501937Y-175680D01*
X502811Y-177722D01*
X503247Y-180055D01*
Y-182389D01*
X502811Y-184722D01*
X501937Y-186764D01*
X500627Y-188514D01*
X499098Y-189680D01*
X497352Y-189972D01*
G01X571152Y-234972D02*
Y-217472D01*
X568532Y-220972D01*
G01Y-234972D02*
X573772D01*
G01X583193D02*
X588652Y-217472D01*
X594111Y-234972D01*
G01X592145Y-228847D02*
X585158D01*
G01X548193Y-172472D02*
X553652Y-189972D01*
X559111Y-172472D01*
G01X575519Y-189972D02*
X566785D01*
Y-172472D01*
X575519D01*
G01X572025Y-180930D02*
X566785D01*
G01X584285Y-189972D02*
Y-172472D01*
X589744D01*
X591490Y-173347D01*
X592582Y-174514D01*
X593019Y-176847D01*
X592582Y-179181D01*
X591272Y-180639D01*
X589744Y-181514D01*
X584285D01*
G01X589744D02*
X593019Y-189972D01*
G01X606152Y-190555D02*
X605715Y-190264D01*
Y-189680D01*
X606152Y-189389D01*
X606589Y-189680D01*
Y-190264D01*
X606152Y-190555D01*
G01X734219Y-217472D02*
Y-234972D01*
X725485D01*
G01X709732D02*
Y-217472D01*
X717811Y-230014D01*
X706893D01*
G01X681735Y-172472D02*
Y-189972D01*
X690469D01*
G01X707532D02*
Y-178306D01*
G01Y-180347D02*
X706659Y-179181D01*
X705348Y-178597D01*
X703820Y-178306D01*
X702292Y-178889D01*
X700982Y-180055D01*
X700108Y-181805D01*
X699672Y-184139D01*
X700108Y-186472D01*
X700982Y-188222D01*
X702292Y-189389D01*
X703820Y-189972D01*
X705348Y-189680D01*
X706659Y-188806D01*
X707532Y-187639D01*
G01X716517Y-195222D02*
X717827Y-195805D01*
X719574Y-195222D01*
X720665Y-194056D01*
X721539Y-192597D01*
X722848Y-187931D01*
X725687Y-178306D01*
G01X718700D02*
X722848Y-187931D01*
G01X735327Y-182097D02*
X742314D01*
X741659Y-180055D01*
X740567Y-178889D01*
X739039Y-178306D01*
X737510Y-178597D01*
X736200Y-179472D01*
X735327Y-181514D01*
X734890Y-183264D01*
Y-185014D01*
X735327Y-186764D01*
X736419Y-188514D01*
X737729Y-189680D01*
X739257Y-189972D01*
X740785Y-189389D01*
X742314Y-187639D01*
G01X753045Y-189972D02*
Y-178306D01*
G01Y-180639D02*
X754137Y-179472D01*
X755229Y-178597D01*
X756757Y-178306D01*
X757848Y-178597D01*
X759159Y-179472D01*
G01X824705Y-218931D02*
X823395Y-218055D01*
X821867Y-217472D01*
X820120D01*
X818155Y-218347D01*
X816627Y-219805D01*
X815535Y-221556D01*
X814662Y-224472D01*
X814443Y-227097D01*
X814880Y-229722D01*
X815535Y-231472D01*
X816845Y-233222D01*
X818374Y-234389D01*
X819902Y-234972D01*
X821430D01*
X822959Y-234389D01*
X824269Y-233514D01*
X825361Y-232348D01*
G01X837402Y-234972D02*
X835655Y-234680D01*
X834127Y-233514D01*
X832817Y-231764D01*
X831943Y-229722D01*
X831507Y-227389D01*
Y-225055D01*
X831943Y-222722D01*
X832817Y-220680D01*
X834127Y-218931D01*
X835655Y-217764D01*
X837402Y-217472D01*
X839148Y-217764D01*
X840677Y-218931D01*
X841987Y-220680D01*
X842861Y-222722D01*
X843297Y-225055D01*
Y-227389D01*
X842861Y-229722D01*
X841987Y-231764D01*
X840677Y-233514D01*
X839148Y-234680D01*
X837402Y-234972D01*
G01X849880D02*
Y-217472D01*
X859924Y-234972D01*
Y-217472D01*
G01X867380Y-234972D02*
Y-217472D01*
X877424Y-234972D01*
Y-217472D01*
G01X887282D02*
X892522D01*
G01X889902D02*
Y-234972D01*
G01X887282D02*
X892522D01*
G01X911769D02*
X903035D01*
Y-217472D01*
X911769D01*
G01X908275Y-225930D02*
X903035D01*
G01X937817Y-234972D02*
X946987Y-217472D01*
G01X937817D02*
X946987Y-234972D01*
G01X955317D02*
Y-217472D01*
G01X964487D02*
Y-234972D01*
G01Y-226222D02*
X955317D01*
G01X823849Y-189972D02*
Y-172472D01*
X828215D01*
X829962Y-173347D01*
X831272Y-174514D01*
X832364Y-176263D01*
X833237Y-178306D01*
X833455Y-181222D01*
X833237Y-184139D01*
X832364Y-186181D01*
X831272Y-187931D01*
X829962Y-189097D01*
X828215Y-189972D01*
X823849D01*
G01X842877Y-182097D02*
X849864D01*
X849209Y-180055D01*
X848117Y-178889D01*
X846589Y-178306D01*
X845060Y-178597D01*
X843750Y-179472D01*
X842877Y-181514D01*
X842440Y-183264D01*
Y-185014D01*
X842877Y-186764D01*
X843969Y-188514D01*
X845279Y-189680D01*
X846807Y-189972D01*
X848335Y-189389D01*
X849864Y-187639D01*
G01X860377Y-187931D02*
X861469Y-189097D01*
X862997Y-189972D01*
X864307D01*
X865617Y-189389D01*
X866490Y-188514D01*
X866927Y-187348D01*
X866709Y-185597D01*
X865835Y-184722D01*
X861905Y-182972D01*
X861032Y-180930D01*
X861469Y-179472D01*
X862342Y-178597D01*
X863652Y-178306D01*
X864962Y-178597D01*
X866272Y-179472D01*
G01X881152Y-178306D02*
Y-189972D01*
G01Y-173639D02*
X880715Y-173347D01*
Y-172764D01*
X881152Y-172472D01*
X881589Y-172764D01*
Y-173347D01*
X881152Y-173639D01*
G01X895595Y-194347D02*
X897124Y-195514D01*
X898870Y-195805D01*
X900398Y-195514D01*
X901709Y-194056D01*
X902582Y-192014D01*
Y-178306D01*
G01Y-180639D02*
X901709Y-179472D01*
X900398Y-178597D01*
X898870Y-178306D01*
X897124Y-178889D01*
X896032Y-180055D01*
X895158Y-182097D01*
X894722Y-184139D01*
X894940Y-185889D01*
X895814Y-187931D01*
X897124Y-189389D01*
X898870Y-189972D01*
X900180Y-189680D01*
X901709Y-188514D01*
X902582Y-187348D01*
G01X912440Y-189972D02*
Y-178306D01*
G01Y-181222D02*
X913314Y-179764D01*
X914624Y-178597D01*
X916370Y-178306D01*
X917898Y-178597D01*
X919209Y-179764D01*
X919864Y-181805D01*
Y-189972D01*
G01X930377Y-182097D02*
X937364D01*
X936709Y-180055D01*
X935617Y-178889D01*
X934089Y-178306D01*
X932560Y-178597D01*
X931250Y-179472D01*
X930377Y-181514D01*
X929940Y-183264D01*
Y-185014D01*
X930377Y-186764D01*
X931469Y-188514D01*
X932779Y-189680D01*
X934307Y-189972D01*
X935835Y-189389D01*
X937364Y-187639D01*
G01X948095Y-189972D02*
Y-178306D01*
G01Y-180639D02*
X949187Y-179472D01*
X950279Y-178597D01*
X951807Y-178306D01*
X952898Y-178597D01*
X954209Y-179472D01*
G01X994852Y-217472D02*
X993105Y-218055D01*
X991795Y-219514D01*
X990922Y-221263D01*
X990267Y-223597D01*
X990049Y-226222D01*
X990267Y-228847D01*
X990922Y-231181D01*
X991795Y-232931D01*
X993105Y-234389D01*
X994852Y-234972D01*
X996598Y-234389D01*
X997909Y-232931D01*
X998782Y-231181D01*
X999437Y-228847D01*
X999655Y-226222D01*
X999437Y-223597D01*
X998782Y-221263D01*
X997909Y-219514D01*
X996598Y-218055D01*
X994852Y-217472D01*
G01X1012352Y-234972D02*
X1013880Y-234680D01*
X1015627Y-233806D01*
X1016719Y-232348D01*
X1017155Y-230305D01*
X1016719Y-228264D01*
X1015409Y-226514D01*
X1013444Y-225639D01*
X1011260D01*
X1009950Y-225055D01*
X1008858Y-223597D01*
X1008422Y-221556D01*
X1009077Y-219514D01*
X1010605Y-218055D01*
X1012352Y-217472D01*
X1014098Y-218055D01*
X1015627Y-219514D01*
X1016282Y-221556D01*
X1015845Y-223597D01*
X1014754Y-225055D01*
X1013444Y-225639D01*
X1011260D01*
X1009295Y-226514D01*
X1007985Y-228264D01*
X1007549Y-230305D01*
X1007985Y-232348D01*
X1009077Y-233806D01*
X1010824Y-234680D01*
X1012352Y-234972D01*
G01X1025922Y-235555D02*
X1033782Y-217472D01*
G01X1043204Y-220389D02*
X1044514Y-218639D01*
X1046042Y-217764D01*
X1047789Y-217472D01*
X1049972Y-218055D01*
X1051500Y-219514D01*
X1051937Y-221263D01*
X1051719Y-223014D01*
X1050845Y-224472D01*
X1046479Y-227389D01*
X1044514Y-229430D01*
X1043204Y-232348D01*
X1042767Y-234972D01*
X1051937D01*
G01X1060049Y-232348D02*
X1061358Y-233806D01*
X1062887Y-234680D01*
X1064852Y-234972D01*
X1066817Y-234389D01*
X1068345Y-233222D01*
X1069437Y-231181D01*
X1069655Y-228847D01*
X1069219Y-226514D01*
X1068127Y-225055D01*
X1066598Y-223889D01*
X1065070Y-223597D01*
X1063542Y-223889D01*
X1061577Y-225055D01*
X1062232Y-217472D01*
X1068127D01*
G01X1078422Y-235555D02*
X1086282Y-217472D01*
G01X1095704Y-220389D02*
X1097014Y-218639D01*
X1098542Y-217764D01*
X1100289Y-217472D01*
X1102472Y-218055D01*
X1104000Y-219514D01*
X1104437Y-221263D01*
X1104219Y-223014D01*
X1103345Y-224472D01*
X1098979Y-227389D01*
X1097014Y-229430D01*
X1095704Y-232348D01*
X1095267Y-234972D01*
X1104437D01*
G01X1117352Y-217472D02*
X1115605Y-218055D01*
X1114295Y-219514D01*
X1113422Y-221263D01*
X1112767Y-223597D01*
X1112549Y-226222D01*
X1112767Y-228847D01*
X1113422Y-231181D01*
X1114295Y-232931D01*
X1115605Y-234389D01*
X1117352Y-234972D01*
X1119098Y-234389D01*
X1120409Y-232931D01*
X1121282Y-231181D01*
X1121937Y-228847D01*
X1122155Y-226222D01*
X1121937Y-223597D01*
X1121282Y-221263D01*
X1120409Y-219514D01*
X1119098Y-218055D01*
X1117352Y-217472D01*
G01X1134852Y-234972D02*
Y-217472D01*
X1132232Y-220972D01*
G01Y-234972D02*
X1137472D01*
G01X1148204Y-227681D02*
X1149732Y-225639D01*
X1151042Y-224472D01*
X1152789Y-223889D01*
X1154317Y-224472D01*
X1155409Y-225639D01*
X1156282Y-227389D01*
X1156500Y-229430D01*
X1156282Y-231181D01*
X1155409Y-232931D01*
X1154098Y-234389D01*
X1152570Y-234972D01*
X1150824Y-234389D01*
X1149295Y-232639D01*
X1148422Y-230014D01*
X1148204Y-227097D01*
X1148640Y-223306D01*
X1149295Y-221263D01*
X1150387Y-219222D01*
X1151915Y-217764D01*
X1153444Y-217472D01*
X1154972Y-218055D01*
X1156064Y-219514D01*
G01X1042549Y-189972D02*
Y-172472D01*
X1046915D01*
X1048662Y-173347D01*
X1049972Y-174514D01*
X1051064Y-176263D01*
X1051937Y-178306D01*
X1052155Y-181222D01*
X1051937Y-184139D01*
X1051064Y-186181D01*
X1049972Y-187931D01*
X1048662Y-189097D01*
X1046915Y-189972D01*
X1042549D01*
G01X1068782D02*
Y-178306D01*
G01Y-180347D02*
X1067909Y-179181D01*
X1066598Y-178597D01*
X1065070Y-178306D01*
X1063542Y-178889D01*
X1062232Y-180055D01*
X1061358Y-181805D01*
X1060922Y-184139D01*
X1061358Y-186472D01*
X1062232Y-188222D01*
X1063542Y-189389D01*
X1065070Y-189972D01*
X1066598Y-189680D01*
X1067909Y-188806D01*
X1068782Y-187639D01*
G01X1082352Y-172472D02*
Y-189972D01*
G01X1079295Y-178306D02*
X1085409D01*
G01X1096577Y-182097D02*
X1103564D01*
X1102909Y-180055D01*
X1101817Y-178889D01*
X1100289Y-178306D01*
X1098760Y-178597D01*
X1097450Y-179472D01*
X1096577Y-181514D01*
X1096140Y-183264D01*
Y-185014D01*
X1096577Y-186764D01*
X1097669Y-188514D01*
X1098979Y-189680D01*
X1100507Y-189972D01*
X1102035Y-189389D01*
X1103564Y-187639D01*
M02*
